# T6G (Grand Teton) — schematic netlist excerpt (pin names and nets, part order shuffled) for the footprints in the layout excerpt that follows; sources: Cadence DE-HDL packaged netlist, KiCad conversion of 04192023_DAF0TMB3IC0_F0TG_MB_C_brd_V02_OCP.brd

C6641  Q_CAP_DIFFBUS  DIFF BUS_0.22UF 6.3V 20% X6S  pkg C0201  page 319 : \1\ = P5E_CPU1_P0_TX_BUF_C_DP<6> ; \2\ = P5E_CPU1_P0_TX_BUF_DP<6>
R3030  Q_RES  100K 1% CHIP  pkg 0402LF  page 127 : A = P3V3_AUX ; B = FM_SMB_1_ALERT_GPU_ISO_N
R4206  Q_RES  1K 1% EMPTY  pkg 0402LF  page 235 : A = P3V3_AUX ; B = U270_0_ADD0

(kicad_pcb
	(version 20260206)
	(generator "pcbnew")
	(generator_version "10.0")
	(general
		(thickness 1.6)
		(legacy_teardrops no)
	)
	(paper "A4")
	(title_block
		(title "04192023_DAF0TMB3IC0_F0TG_MB_C_brd_V02_OCP.brd")
		(comment 1 "Grand Teton / footprints 356-358 of 8354")
	)
	(layers
		(0 "F.Cu" signal "TOP")
		(4 "In1.Cu" signal "GND")
		(6 "In2.Cu" signal "IN1")
		(8 "In3.Cu" signal "GND1")
		(10 "In4.Cu" signal "IN2")
		(12 "In5.Cu" signal "GND2")
		(14 "In6.Cu" signal "IN3")
		(16 "In7.Cu" signal "GND3")
		(18 "In8.Cu" signal "VCC")
		(20 "In9.Cu" signal "VCC1")
		(22 "In10.Cu" signal "GND4")
		(24 "In11.Cu" signal "IN4")
		(26 "In12.Cu" signal "GND5")
		(28 "In13.Cu" signal "IN5")
		(30 "In14.Cu" signal "GND6")
		(32 "In15.Cu" signal "IN6")
		(34 "In16.Cu" signal "GND7")
		(2 "B.Cu" signal "BOTTOM")
		(9 "F.Adhes" user "F.Adhesive")
		(11 "B.Adhes" user "B.Adhesive")
		(13 "F.Paste" user "Package Geometry/Pastemask Top")
		(15 "B.Paste" user "Package Geometry/Pastemask Bottom")
		(5 "F.SilkS" user "Ref Des/Silkscreen Top")
		(7 "B.SilkS" user "Ref Des/Silkscreen Bottom")
		(1 "F.Mask" user "Board Geometry/Soldermask Top")
		(3 "B.Mask" user "Board Geometry/Soldermask Bottom")
		(17 "Dwgs.User" user "User.Drawings")
		(19 "Cmts.User" user "User.Comments")
		(21 "Eco1.User" user "User.Eco1")
		(23 "Eco2.User" user "User.Eco2")
		(25 "Edge.Cuts" user "Board Geometry/Outline")
		(27 "Margin" user)
		(31 "F.CrtYd" user "Package Geometry/Place Bound Top")
		(29 "B.CrtYd" user "Package Geometry/Place Bound Bottom")
		(35 "F.Fab" user "Ref Des/Assembly Top")
		(33 "B.Fab" user "Ref Des/Assembly Bottom")
	)
	(footprint ""
		(layer "F.Cu")
		(at 67.062604 -408.517344 -90)
		(property "Reference" "C6641"
			(at 0 0 270)
			(layer "F.SilkS")
			(hide yes)
			(effects
				(font
					(size 1.27 1.27)
				)
			)
		)
		(property "Value" ""
			(at 0 0 270)
			(layer "F.Fab")
			(effects
				(font
					(size 1.27 1.27)
				)
			)
		)
		(duplicate_pad_numbers_are_jumpers no)
		(fp_line
			(start -0.299974 0.150114)
			(end -0.299974 -0.150114)
			(stroke
				(width 0.1)
				(type default)
			)
			(layer "F.Fab")
		)
		(fp_line
			(start 0.299974 0.150114)
			(end -0.299974 0.150114)
			(stroke
				(width 0.1)
				(type default)
			)
			(layer "F.Fab")
		)
		(fp_line
			(start -0.299974 -0.150114)
			(end 0.299974 -0.150114)
			(stroke
				(width 0.1)
				(type default)
			)
			(layer "F.Fab")
		)
		(fp_line
			(start 0.299974 -0.150114)
			(end 0.299974 0.150114)
			(stroke
				(width 0.1)
				(type default)
			)
			(layer "F.Fab")
		)
		(pad "1" smd rect
			(at -0.2667 0 270)
			(size 0.3048 0.381)
			(layers "F.Cu" "F.Mask" "F.Paste")
			(net "P5E_CPU1_P0_TX_BUF_C_DP<6>")
		)
		(pad "2" smd rect
			(at 0.2667 0 270)
			(size 0.3048 0.381)
			(layers "F.Cu" "F.Mask" "F.Paste")
			(net "P5E_CPU1_P0_TX_BUF_DP<6>")
		)
	)
	(footprint ""
		(layer "F.Cu")
		(at 367.050066 -427.400212 -90)
		(property "Reference" "R4206"
			(at 0 0 270)
			(layer "F.SilkS")
			(hide yes)
			(effects
				(font
					(size 1.27 1.27)
				)
			)
		)
		(property "Value" ""
			(at 0 0 270)
			(layer "F.Fab")
			(effects
				(font
					(size 1.27 1.27)
				)
			)
		)
		(duplicate_pad_numbers_are_jumpers no)
		(fp_line
			(start -0.7874 0.4064)
			(end -0.7874 -0.4064)
			(stroke
				(width 0.1524)
				(type default)
			)
			(layer "F.SilkS")
		)
		(fp_line
			(start 0.7874 0.4064)
			(end -0.7874 0.4064)
			(stroke
				(width 0.1524)
				(type default)
			)
			(layer "F.SilkS")
		)
		(fp_line
			(start -0.7874 -0.4064)
			(end 0.7874 -0.4064)
			(stroke
				(width 0.1524)
				(type default)
			)
			(layer "F.SilkS")
		)
		(fp_line
			(start 0.7874 -0.4064)
			(end 0.7874 0.4064)
			(stroke
				(width 0.1524)
				(type default)
			)
			(layer "F.SilkS")
		)
		(fp_line
			(start -0.67945 0.3048)
			(end -0.67945 -0.305054)
			(stroke
				(width 0.1)
				(type default)
			)
			(layer "F.Fab")
		)
		(fp_line
			(start -0.12065 0.3048)
			(end -0.67945 0.3048)
			(stroke
				(width 0.1)
				(type default)
			)
			(layer "F.Fab")
		)
		(fp_line
			(start 0.120396 0.3048)
			(end 0.120396 0.2794)
			(stroke
				(width 0.1)
				(type default)
			)
			(layer "F.Fab")
		)
		(fp_line
			(start 0.67945 0.3048)
			(end 0.120396 0.3048)
			(stroke
				(width 0.1)
				(type default)
			)
			(layer "F.Fab")
		)
		(fp_line
			(start -0.12065 0.2794)
			(end -0.12065 0.3048)
			(stroke
				(width 0.1)
				(type default)
			)
			(layer "F.Fab")
		)
		(fp_line
			(start 0.120396 0.2794)
			(end -0.12065 0.2794)
			(stroke
				(width 0.1)
				(type default)
			)
			(layer "F.Fab")
		)
		(fp_line
			(start -0.12065 -0.2794)
			(end 0.12065 -0.2794)
			(stroke
				(width 0.1)
				(type default)
			)
			(layer "F.Fab")
		)
		(fp_line
			(start 0.12065 -0.2794)
			(end 0.12065 -0.3048)
			(stroke
				(width 0.1)
				(type default)
			)
			(layer "F.Fab")
		)
		(fp_line
			(start 0.12065 -0.3048)
			(end 0.67945 -0.3048)
			(stroke
				(width 0.1)
				(type default)
			)
			(layer "F.Fab")
		)
		(fp_line
			(start 0.67945 -0.3048)
			(end 0.67945 0.3048)
			(stroke
				(width 0.1)
				(type default)
			)
			(layer "F.Fab")
		)
		(fp_line
			(start -0.67945 -0.305054)
			(end -0.12065 -0.305054)
			(stroke
				(width 0.1)
				(type default)
			)
			(layer "F.Fab")
		)
		(fp_line
			(start -0.12065 -0.305054)
			(end -0.12065 -0.2794)
			(stroke
				(width 0.1)
				(type default)
			)
			(layer "F.Fab")
		)
		(pad "1" smd circle
			(at -0.40005 0 270)
			(size 0 0)
			(layers "F.Cu" "F.Mask" "F.Paste")
			(net "P3V3_AUX")
		)
		(pad "2" smd circle
			(at 0.40005 0 270)
			(size 0 0)
			(layers "F.Cu" "F.Mask" "F.Paste")
			(net "U270_0_ADD0")
		)
	)
	(footprint ""
		(layer "F.Cu")
		(at 116.078 -417.957 -90)
		(property "Reference" "R3030"
			(at 0 0 270)
			(layer "F.SilkS")
			(hide yes)
			(effects
				(font
					(size 1.27 1.27)
				)
			)
		)
		(property "Value" ""
			(at 0 0 270)
			(layer "F.Fab")
			(effects
				(font
					(size 1.27 1.27)
				)
			)
		)
		(duplicate_pad_numbers_are_jumpers no)
		(fp_line
			(start -0.7874 0.4064)
			(end -0.7874 -0.4064)
			(stroke
				(width 0.1524)
				(type default)
			)
			(layer "F.SilkS")
		)
		(fp_line
			(start 0.7874 0.4064)
			(end -0.7874 0.4064)
			(stroke
				(width 0.1524)
				(type default)
			)
			(layer "F.SilkS")
		)
		(fp_line
			(start -0.7874 -0.4064)
			(end 0.7874 -0.4064)
			(stroke
				(width 0.1524)
				(type default)
			)
			(layer "F.SilkS")
		)
		(fp_line
			(start 0.7874 -0.4064)
			(end 0.7874 0.4064)
			(stroke
				(width 0.1524)
				(type default)
			)
			(layer "F.SilkS")
		)
		(fp_line
			(start -0.67945 0.3048)
			(end -0.67945 -0.305054)
			(stroke
				(width 0.1)
				(type default)
			)
			(layer "F.Fab")
		)
		(fp_line
			(start -0.12065 0.3048)
			(end -0.67945 0.3048)
			(stroke
				(width 0.1)
				(type default)
			)
			(layer "F.Fab")
		)
		(fp_line
			(start 0.120396 0.3048)
			(end 0.120396 0.2794)
			(stroke
				(width 0.1)
				(type default)
			)
			(layer "F.Fab")
		)
		(fp_line
			(start 0.67945 0.3048)
			(end 0.120396 0.3048)
			(stroke
				(width 0.1)
				(type default)
			)
			(layer "F.Fab")
		)
		(fp_line
			(start -0.12065 0.2794)
			(end -0.12065 0.3048)
			(stroke
				(width 0.1)
				(type default)
			)
			(layer "F.Fab")
		)
		(fp_line
			(start 0.120396 0.2794)
			(end -0.12065 0.2794)
			(stroke
				(width 0.1)
				(type default)
			)
			(layer "F.Fab")
		)
		(fp_line
			(start -0.12065 -0.2794)
			(end 0.12065 -0.2794)
			(stroke
				(width 0.1)
				(type default)
			)
			(layer "F.Fab")
		)
		(fp_line
			(start 0.12065 -0.2794)
			(end 0.12065 -0.3048)
			(stroke
				(width 0.1)
				(type default)
			)
			(layer "F.Fab")
		)
		(fp_line
			(start 0.12065 -0.3048)
			(end 0.67945 -0.3048)
			(stroke
				(width 0.1)
				(type default)
			)
			(layer "F.Fab")
		)
		(fp_line
			(start 0.67945 -0.3048)
			(end 0.67945 0.3048)
			(stroke
				(width 0.1)
				(type default)
			)
			(layer "F.Fab")
		)
		(fp_line
			(start -0.67945 -0.305054)
			(end -0.12065 -0.305054)
			(stroke
				(width 0.1)
				(type default)
			)
			(layer "F.Fab")
		)
		(fp_line
			(start -0.12065 -0.305054)
			(end -0.12065 -0.2794)
			(stroke
				(width 0.1)
				(type default)
			)
			(layer "F.Fab")
		)
		(pad "1" smd circle
			(at -0.40005 0 270)
			(size 0 0)
			(layers "F.Cu" "F.Mask" "F.Paste")
			(net "P3V3_AUX")
		)
		(pad "2" smd circle
			(at 0.40005 0 270)
			(size 0 0)
			(layers "F.Cu" "F.Mask" "F.Paste")
			(net "FM_SMB_1_ALERT_GPU_ISO_N")
		)
	)
)
